(kicad_pcb
	(version 20260206)
	(generator "pcbnew")
	(generator_version "10.0")
	(general
		(thickness 1.6)
		(legacy_teardrops no)
	)
	(paper "A4")
	(title_block
		(title "01162023_DA0F0TEBIF0_F0T_Expander_BD_F_brd_V02_OCP.brd")
		(comment 1 "Grand Teton / footprints 9401-9408 of 9728")
	)
	(layers
		(0 "F.Cu" signal "TOP")
		(4 "In1.Cu" signal "GND")
		(6 "In2.Cu" signal "VCC")
		(8 "In3.Cu" signal "VCC1")
		(10 "In4.Cu" signal "GND1")
		(12 "In5.Cu" signal "IN1")
		(14 "In6.Cu" signal "GND2")
		(16 "In7.Cu" signal "IN2")
		(18 "In8.Cu" signal "GND3")
		(20 "In9.Cu" signal "IN3")
		(22 "In10.Cu" signal "GND4")
		(24 "In11.Cu" signal "IN4")
		(26 "In12.Cu" signal "GND5")
		(28 "In13.Cu" signal "IN5")
		(30 "In14.Cu" signal "GND6")
		(32 "In15.Cu" signal "IN6")
		(34 "In16.Cu" signal "GND7")
		(2 "B.Cu" signal "BOTTOM")
		(9 "F.Adhes" user "F.Adhesive")
		(11 "B.Adhes" user "B.Adhesive")
		(13 "F.Paste" user "Package Geometry/Pastemask Top")
		(15 "B.Paste" user "Package Geometry/Pastemask Bottom")
		(5 "F.SilkS" user "Ref Des/Silkscreen Top")
		(7 "B.SilkS" user "Ref Des/Silkscreen Bottom")
		(1 "F.Mask" user "Board Geometry/Soldermask Top")
		(3 "B.Mask" user "Board Geometry/Soldermask Bottom")
		(17 "Dwgs.User" user "User.Drawings")
		(19 "Cmts.User" user "User.Comments")
		(21 "Eco1.User" user "User.Eco1")
		(23 "Eco2.User" user "User.Eco2")
		(25 "Edge.Cuts" user "Board Geometry/Outline")
		(27 "Margin" user)
		(31 "F.CrtYd" user "Package Geometry/Place Bound Top")
		(29 "B.CrtYd" user "Package Geometry/Place Bound Bottom")
		(35 "F.Fab" user "Ref Des/Assembly Top")
		(33 "B.Fab" user "Ref Des/Assembly Bottom")
	)
	(footprint ""
		(layer "B.Cu")
		(at 204.377036 -363.00029)
		(property "Reference" "R495"
			(at 0 0 0)
			(layer "B.SilkS")
			(hide yes)
			(effects
				(font
					(size 1.27 1.27)
				)
				(justify mirror)
			)
		)
		(property "Value" ""
			(at 0 0 0)
			(layer "B.Fab")
			(effects
				(font
					(size 1.27 1.27)
				)
				(justify mirror)
			)
		)
		(duplicate_pad_numbers_are_jumpers no)
		(fp_line
			(start -0.7874 -0.4064)
			(end -0.7874 0.4064)
			(stroke
				(width 0.1524)
				(type default)
			)
			(layer "B.SilkS")
		)
		(fp_line
			(start -0.7874 0.4064)
			(end 0.7874 0.4064)
			(stroke
				(width 0.1524)
				(type default)
			)
			(layer "B.SilkS")
		)
		(fp_line
			(start 0.7874 -0.4064)
			(end -0.7874 -0.4064)
			(stroke
				(width 0.1524)
				(type default)
			)
			(layer "B.SilkS")
		)
		(fp_line
			(start 0.7874 0.4064)
			(end 0.7874 -0.4064)
			(stroke
				(width 0.1524)
				(type default)
			)
			(layer "B.SilkS")
		)
		(fp_line
			(start -0.67945 -0.3048)
			(end -0.67945 0.3048)
			(stroke
				(width 0.1)
				(type default)
			)
			(layer "B.Fab")
		)
		(fp_line
			(start -0.67945 0.3048)
			(end -0.120396 0.3048)
			(stroke
				(width 0.1)
				(type default)
			)
			(layer "B.Fab")
		)
		(fp_line
			(start -0.12065 -0.3048)
			(end -0.67945 -0.3048)
			(stroke
				(width 0.1)
				(type default)
			)
			(layer "B.Fab")
		)
		(fp_line
			(start -0.12065 -0.2794)
			(end -0.12065 -0.3048)
			(stroke
				(width 0.1)
				(type default)
			)
			(layer "B.Fab")
		)
		(fp_line
			(start -0.120396 0.2794)
			(end 0.12065 0.2794)
			(stroke
				(width 0.1)
				(type default)
			)
			(layer "B.Fab")
		)
		(fp_line
			(start -0.120396 0.3048)
			(end -0.120396 0.2794)
			(stroke
				(width 0.1)
				(type default)
			)
			(layer "B.Fab")
		)
		(fp_line
			(start 0.12065 -0.305054)
			(end 0.12065 -0.2794)
			(stroke
				(width 0.1)
				(type default)
			)
			(layer "B.Fab")
		)
		(fp_line
			(start 0.12065 -0.2794)
			(end -0.12065 -0.2794)
			(stroke
				(width 0.1)
				(type default)
			)
			(layer "B.Fab")
		)
		(fp_line
			(start 0.12065 0.2794)
			(end 0.12065 0.3048)
			(stroke
				(width 0.1)
				(type default)
			)
			(layer "B.Fab")
		)
		(fp_line
			(start 0.12065 0.3048)
			(end 0.67945 0.3048)
			(stroke
				(width 0.1)
				(type default)
			)
			(layer "B.Fab")
		)
		(fp_line
			(start 0.67945 -0.305054)
			(end 0.12065 -0.305054)
			(stroke
				(width 0.1)
				(type default)
			)
			(layer "B.Fab")
		)
		(fp_line
			(start 0.67945 0.3048)
			(end 0.67945 -0.305054)
			(stroke
				(width 0.1)
				(type default)
			)
			(layer "B.Fab")
		)
		(pad "1" smd circle
			(at 0.40005 0 180)
			(size 0 0)
			(layers "B.Cu" "B.Mask" "B.Paste")
			(net "HSC_P12V_EN")
		)
		(pad "2" smd circle
			(at -0.40005 0 180)
			(size 0 0)
			(layers "B.Cu" "B.Mask" "B.Paste")
			(net "GND")
		)
	)
	(footprint ""
		(layer "B.Cu")
		(at 184.772046 -112.421924 180)
		(property "Reference" "R162"
			(at 0 0 0)
			(layer "B.SilkS")
			(hide yes)
			(effects
				(font
					(size 1.27 1.27)
				)
				(justify mirror)
			)
		)
		(property "Value" ""
			(at 0 0 0)
			(layer "B.Fab")
			(effects
				(font
					(size 1.27 1.27)
				)
				(justify mirror)
			)
		)
		(duplicate_pad_numbers_are_jumpers no)
		(fp_line
			(start 0.7874 0.4064)
			(end 0.7874 -0.4064)
			(stroke
				(width 0.1524)
				(type default)
			)
			(layer "B.SilkS")
		)
		(fp_line
			(start 0.7874 -0.4064)
			(end -0.7874 -0.4064)
			(stroke
				(width 0.1524)
				(type default)
			)
			(layer "B.SilkS")
		)
		(fp_line
			(start -0.7874 0.4064)
			(end 0.7874 0.4064)
			(stroke
				(width 0.1524)
				(type default)
			)
			(layer "B.SilkS")
		)
		(fp_line
			(start -0.7874 -0.4064)
			(end -0.7874 0.4064)
			(stroke
				(width 0.1524)
				(type default)
			)
			(layer "B.SilkS")
		)
		(fp_line
			(start 0.67945 0.3048)
			(end 0.67945 -0.305054)
			(stroke
				(width 0.1)
				(type default)
			)
			(layer "B.Fab")
		)
		(fp_line
			(start 0.67945 -0.305054)
			(end 0.12065 -0.305054)
			(stroke
				(width 0.1)
				(type default)
			)
			(layer "B.Fab")
		)
		(fp_line
			(start 0.12065 0.3048)
			(end 0.67945 0.3048)
			(stroke
				(width 0.1)
				(type default)
			)
			(layer "B.Fab")
		)
		(fp_line
			(start 0.12065 0.2794)
			(end 0.12065 0.3048)
			(stroke
				(width 0.1)
				(type default)
			)
			(layer "B.Fab")
		)
		(fp_line
			(start 0.12065 -0.2794)
			(end -0.12065 -0.2794)
			(stroke
				(width 0.1)
				(type default)
			)
			(layer "B.Fab")
		)
		(fp_line
			(start 0.12065 -0.305054)
			(end 0.12065 -0.2794)
			(stroke
				(width 0.1)
				(type default)
			)
			(layer "B.Fab")
		)
		(fp_line
			(start -0.120396 0.3048)
			(end -0.120396 0.2794)
			(stroke
				(width 0.1)
				(type default)
			)
			(layer "B.Fab")
		)
		(fp_line
			(start -0.120396 0.2794)
			(end 0.12065 0.2794)
			(stroke
				(width 0.1)
				(type default)
			)
			(layer "B.Fab")
		)
		(fp_line
			(start -0.12065 -0.2794)
			(end -0.12065 -0.3048)
			(stroke
				(width 0.1)
				(type default)
			)
			(layer "B.Fab")
		)
		(fp_line
			(start -0.12065 -0.3048)
			(end -0.67945 -0.3048)
			(stroke
				(width 0.1)
				(type default)
			)
			(layer "B.Fab")
		)
		(fp_line
			(start -0.67945 0.3048)
			(end -0.120396 0.3048)
			(stroke
				(width 0.1)
				(type default)
			)
			(layer "B.Fab")
		)
		(fp_line
			(start -0.67945 -0.3048)
			(end -0.67945 0.3048)
			(stroke
				(width 0.1)
				(type default)
			)
			(layer "B.Fab")
		)
		(pad "1" smd circle
			(at 0.40005 0)
			(size 0 0)
			(layers "B.Cu" "B.Mask" "B.Paste")
			(net "SMB_NIC3_R_SCL")
		)
		(pad "2" smd circle
			(at -0.40005 0)
			(size 0 0)
			(layers "B.Cu" "B.Mask" "B.Paste")
			(net "P3V3_NIC3")
		)
	)
	(footprint ""
		(layer "B.Cu")
		(at 348.98838 -318.542416 180)
		(property "Reference" "C4309"
			(at 0 0 0)
			(layer "B.SilkS")
			(hide yes)
			(effects
				(font
					(size 1.27 1.27)
				)
				(justify mirror)
			)
		)
		(property "Value" ""
			(at 0 0 0)
			(layer "B.Fab")
			(effects
				(font
					(size 1.27 1.27)
				)
				(justify mirror)
			)
		)
		(duplicate_pad_numbers_are_jumpers no)
		(fp_line
			(start 0.299974 0.150114)
			(end 0.299974 -0.150114)
			(stroke
				(width 0.1)
				(type default)
			)
			(layer "B.Fab")
		)
		(fp_line
			(start 0.299974 -0.150114)
			(end -0.299974 -0.150114)
			(stroke
				(width 0.1)
				(type default)
			)
			(layer "B.Fab")
		)
		(fp_line
			(start -0.299974 0.150114)
			(end 0.299974 0.150114)
			(stroke
				(width 0.1)
				(type default)
			)
			(layer "B.Fab")
		)
		(fp_line
			(start -0.299974 -0.150114)
			(end -0.299974 0.150114)
			(stroke
				(width 0.1)
				(type default)
			)
			(layer "B.Fab")
		)
		(pad "1" smd rect
			(at 0.2667 0)
			(size 0.3048 0.381)
			(layers "B.Cu" "B.Mask" "B.Paste")
			(net "P0V8_SERDES_VDDA_PEX2")
		)
		(pad "2" smd rect
			(at -0.2667 0)
			(size 0.3048 0.381)
			(layers "B.Cu" "B.Mask" "B.Paste")
			(net "GND")
		)
	)
	(footprint ""
		(layer "B.Cu")
		(at 237.903512 -234.728004 90)
		(property "Reference" "R6195"
			(at 0 0 90)
			(layer "B.SilkS")
			(hide yes)
			(effects
				(font
					(size 1.27 1.27)
				)
				(justify mirror)
			)
		)
		(property "Value" ""
			(at 0 0 90)
			(layer "B.Fab")
			(effects
				(font
					(size 1.27 1.27)
				)
				(justify mirror)
			)
		)
		(duplicate_pad_numbers_are_jumpers no)
		(fp_line
			(start 0.7874 -0.4064)
			(end -0.7874 -0.4064)
			(stroke
				(width 0.1524)
				(type default)
			)
			(layer "B.SilkS")
		)
		(fp_line
			(start -0.7874 -0.4064)
			(end -0.7874 0.4064)
			(stroke
				(width 0.1524)
				(type default)
			)
			(layer "B.SilkS")
		)
		(fp_line
			(start 0.7874 0.4064)
			(end 0.7874 -0.4064)
			(stroke
				(width 0.1524)
				(type default)
			)
			(layer "B.SilkS")
		)
		(fp_line
			(start -0.7874 0.4064)
			(end 0.7874 0.4064)
			(stroke
				(width 0.1524)
				(type default)
			)
			(layer "B.SilkS")
		)
		(fp_line
			(start 0.67945 -0.305054)
			(end 0.12065 -0.305054)
			(stroke
				(width 0.1)
				(type default)
			)
			(layer "B.Fab")
		)
		(fp_line
			(start 0.12065 -0.305054)
			(end 0.12065 -0.2794)
			(stroke
				(width 0.1)
				(type default)
			)
			(layer "B.Fab")
		)
		(fp_line
			(start -0.12065 -0.3048)
			(end -0.67945 -0.3048)
			(stroke
				(width 0.1)
				(type default)
			)
			(layer "B.Fab")
		)
		(fp_line
			(start -0.67945 -0.3048)
			(end -0.67945 0.3048)
			(stroke
				(width 0.1)
				(type default)
			)
			(layer "B.Fab")
		)
		(fp_line
			(start 0.12065 -0.2794)
			(end -0.12065 -0.2794)
			(stroke
				(width 0.1)
				(type default)
			)
			(layer "B.Fab")
		)
		(fp_line
			(start -0.12065 -0.2794)
			(end -0.12065 -0.3048)
			(stroke
				(width 0.1)
				(type default)
			)
			(layer "B.Fab")
		)
		(fp_line
			(start 0.12065 0.2794)
			(end 0.12065 0.3048)
			(stroke
				(width 0.1)
				(type default)
			)
			(layer "B.Fab")
		)
		(fp_line
			(start -0.120396 0.2794)
			(end 0.12065 0.2794)
			(stroke
				(width 0.1)
				(type default)
			)
			(layer "B.Fab")
		)
		(fp_line
			(start 0.67945 0.3048)
			(end 0.67945 -0.305054)
			(stroke
				(width 0.1)
				(type default)
			)
			(layer "B.Fab")
		)
		(fp_line
			(start 0.12065 0.3048)
			(end 0.67945 0.3048)
			(stroke
				(width 0.1)
				(type default)
			)
			(layer "B.Fab")
		)
		(fp_line
			(start -0.120396 0.3048)
			(end -0.120396 0.2794)
			(stroke
				(width 0.1)
				(type default)
			)
			(layer "B.Fab")
		)
		(fp_line
			(start -0.67945 0.3048)
			(end -0.120396 0.3048)
			(stroke
				(width 0.1)
				(type default)
			)
			(layer "B.Fab")
		)
		(pad "1" smd circle
			(at 0.40005 0 270)
			(size 0 0)
			(layers "B.Cu" "B.Mask" "B.Paste")
			(net "GND")
		)
		(pad "2" smd circle
			(at -0.40005 0 270)
			(size 0 0)
			(layers "B.Cu" "B.Mask" "B.Paste")
			(net "SSD13_PWRDIS_BIC_R")
		)
	)
	(footprint ""
		(layer "B.Cu")
		(at 404.149814 -301.599854 -90)
		(property "Reference" "C1986"
			(at 0 0 90)
			(layer "B.SilkS")
			(hide yes)
			(effects
				(font
					(size 1.27 1.27)
				)
				(justify mirror)
			)
		)
		(property "Value" ""
			(at 0 0 90)
			(layer "B.Fab")
			(effects
				(font
					(size 1.27 1.27)
				)
				(justify mirror)
			)
		)
		(duplicate_pad_numbers_are_jumpers no)
		(fp_line
			(start -0.299974 0.150114)
			(end 0.299974 0.150114)
			(stroke
				(width 0.1)
				(type default)
			)
			(layer "B.Fab")
		)
		(fp_line
			(start 0.299974 0.150114)
			(end 0.299974 -0.150114)
			(stroke
				(width 0.1)
				(type default)
			)
			(layer "B.Fab")
		)
		(fp_line
			(start -0.299974 -0.150114)
			(end -0.299974 0.150114)
			(stroke
				(width 0.1)
				(type default)
			)
			(layer "B.Fab")
		)
		(fp_line
			(start 0.299974 -0.150114)
			(end -0.299974 -0.150114)
			(stroke
				(width 0.1)
				(type default)
			)
			(layer "B.Fab")
		)
		(pad "1" smd rect
			(at 0.2667 0 90)
			(size 0.3048 0.381)
			(layers "B.Cu" "B.Mask" "B.Paste")
			(net "P0V8_SERDES_VDDA_PEX3")
		)
		(pad "2" smd rect
			(at -0.2667 0 90)
			(size 0.3048 0.381)
			(layers "B.Cu" "B.Mask" "B.Paste")
			(net "GND")
		)
	)
	(footprint ""
		(layer "B.Cu")
		(at 229.867714 -214.704168 90)
		(property "Reference" "C2007"
			(at 0 0 90)
			(layer "B.SilkS")
			(hide yes)
			(effects
				(font
					(size 1.27 1.27)
				)
				(justify mirror)
			)
		)
		(property "Value" ""
			(at 0 0 90)
			(layer "B.Fab")
			(effects
				(font
					(size 1.27 1.27)
				)
				(justify mirror)
			)
		)
		(duplicate_pad_numbers_are_jumpers no)
		(fp_line
			(start 0.69215 -0.2921)
			(end -0.69215 -0.2921)
			(stroke
				(width 0.1524)
				(type default)
			)
			(layer "B.SilkS")
		)
		(fp_line
			(start -0.69215 -0.2921)
			(end -0.69215 0.2921)
			(stroke
				(width 0.1524)
				(type default)
			)
			(layer "B.SilkS")
		)
		(fp_line
			(start 0.69215 0.2921)
			(end 0.69215 -0.2921)
			(stroke
				(width 0.1524)
				(type default)
			)
			(layer "B.SilkS")
		)
		(fp_line
			(start -0.69215 0.2921)
			(end 0.69215 0.2921)
			(stroke
				(width 0.1524)
				(type default)
			)
			(layer "B.SilkS")
		)
		(fp_line
			(start 0.51435 -0.2794)
			(end -0.51435 -0.2794)
			(stroke
				(width 0.1)
				(type default)
			)
			(layer "B.Fab")
		)
		(fp_line
			(start -0.51435 -0.2794)
			(end -0.51435 0.2794)
			(stroke
				(width 0.1)
				(type default)
			)
			(layer "B.Fab")
		)
		(fp_line
			(start 0.51435 0.2794)
			(end 0.51435 -0.2794)
			(stroke
				(width 0.1)
				(type default)
			)
			(layer "B.Fab")
		)
		(fp_line
			(start -0.51435 0.2794)
			(end 0.51435 0.2794)
			(stroke
				(width 0.1)
				(type default)
			)
			(layer "B.Fab")
		)
		(pad "1" smd circle
			(at 0.40005 0 270)
			(size 0 0)
			(layers "B.Cu" "B.Mask" "B.Paste")
			(net "P3V3_AUX")
		)
		(pad "2" smd circle
			(at -0.40005 0 270)
			(size 0 0)
			(layers "B.Cu" "B.Mask" "B.Paste")
			(net "GND")
		)
		(zone
			(layer "B.Cu")
			(hatch none 0.5)
			(connect_pads
				(clearance 0)
			)
			(min_thickness 0.25)
			(keepout
				(tracks not_allowed)
				(vias allowed)
				(pads allowed)
				(copperpour not_allowed)
				(footprints allowed)
			)
			(placement
				(enabled no)
				(sheetname "")
			)
			(fill
				(thermal_gap 0.5)
				(thermal_bridge_width 0.5)
				(island_removal_mode 0)
			)
			(polygon
				(pts
					(xy 229.955344 -214.894668) (xy 230.01351 -214.803228) (xy 230.01351 -214.603838) (xy 229.955344 -214.513668)
					(xy 229.780084 -214.513668) (xy 229.721664 -214.603838) (xy 229.721664 -214.803228) (xy 229.77983 -214.894668)
				)
			)
		)
	)
	(footprint ""
		(layer "B.Cu")
		(at 378.069602 -243.428012 180)
		(property "Reference" "R935"
			(at 0 0 0)
			(layer "B.SilkS")
			(hide yes)
			(effects
				(font
					(size 1.27 1.27)
				)
				(justify mirror)
			)
		)
		(property "Value" ""
			(at 0 0 0)
			(layer "B.Fab")
			(effects
				(font
					(size 1.27 1.27)
				)
				(justify mirror)
			)
		)
		(duplicate_pad_numbers_are_jumpers no)
		(fp_line
			(start 0.7874 0.4064)
			(end 0.7874 -0.4064)
			(stroke
				(width 0.1524)
				(type default)
			)
			(layer "B.SilkS")
		)
		(fp_line
			(start 0.7874 -0.4064)
			(end -0.7874 -0.4064)
			(stroke
				(width 0.1524)
				(type default)
			)
			(layer "B.SilkS")
		)
		(fp_line
			(start -0.7874 0.4064)
			(end 0.7874 0.4064)
			(stroke
				(width 0.1524)
				(type default)
			)
			(layer "B.SilkS")
		)
		(fp_line
			(start -0.7874 -0.4064)
			(end -0.7874 0.4064)
			(stroke
				(width 0.1524)
				(type default)
			)
			(layer "B.SilkS")
		)
		(fp_line
			(start 0.67945 0.3048)
			(end 0.67945 -0.305054)
			(stroke
				(width 0.1)
				(type default)
			)
			(layer "B.Fab")
		)
		(fp_line
			(start 0.67945 -0.305054)
			(end 0.12065 -0.305054)
			(stroke
				(width 0.1)
				(type default)
			)
			(layer "B.Fab")
		)
		(fp_line
			(start 0.12065 0.3048)
			(end 0.67945 0.3048)
			(stroke
				(width 0.1)
				(type default)
			)
			(layer "B.Fab")
		)
		(fp_line
			(start 0.12065 0.2794)
			(end 0.12065 0.3048)
			(stroke
				(width 0.1)
				(type default)
			)
			(layer "B.Fab")
		)
		(fp_line
			(start 0.12065 -0.2794)
			(end -0.12065 -0.2794)
			(stroke
				(width 0.1)
				(type default)
			)
			(layer "B.Fab")
		)
		(fp_line
			(start 0.12065 -0.305054)
			(end 0.12065 -0.2794)
			(stroke
				(width 0.1)
				(type default)
			)
			(layer "B.Fab")
		)
		(fp_line
			(start -0.120396 0.3048)
			(end -0.120396 0.2794)
			(stroke
				(width 0.1)
				(type default)
			)
			(layer "B.Fab")
		)
		(fp_line
			(start -0.120396 0.2794)
			(end 0.12065 0.2794)
			(stroke
				(width 0.1)
				(type default)
			)
			(layer "B.Fab")
		)
		(fp_line
			(start -0.12065 -0.2794)
			(end -0.12065 -0.3048)
			(stroke
				(width 0.1)
				(type default)
			)
			(layer "B.Fab")
		)
		(fp_line
			(start -0.12065 -0.3048)
			(end -0.67945 -0.3048)
			(stroke
				(width 0.1)
				(type default)
			)
			(layer "B.Fab")
		)
		(fp_line
			(start -0.67945 0.3048)
			(end -0.120396 0.3048)
			(stroke
				(width 0.1)
				(type default)
			)
			(layer "B.Fab")
		)
		(fp_line
			(start -0.67945 -0.3048)
			(end -0.67945 0.3048)
			(stroke
				(width 0.1)
				(type default)
			)
			(layer "B.Fab")
		)
		(pad "1" smd circle
			(at 0.40005 0)
			(size 0 0)
			(layers "B.Cu" "B.Mask" "B.Paste")
			(net "UART_PEX0_SDB_BUF_R_TX")
		)
		(pad "2" smd circle
			(at -0.40005 0)
			(size 0 0)
			(layers "B.Cu" "B.Mask" "B.Paste")
			(net "UART_PEX0_SDB_BUF_TX")
		)
	)
	(footprint ""
		(layer "B.Cu")
		(at 166.725092 -297.79976 -90)
		(property "Reference" "C1388"
			(at 0 0 90)
			(layer "B.SilkS")
			(hide yes)
			(effects
				(font
					(size 1.27 1.27)
				)
				(justify mirror)
			)
		)
		(property "Value" ""
			(at 0 0 90)
			(layer "B.Fab")
			(effects
				(font
					(size 1.27 1.27)
				)
				(justify mirror)
			)
		)
		(duplicate_pad_numbers_are_jumpers no)
		(fp_line
			(start -0.299974 0.150114)
			(end 0.299974 0.150114)
			(stroke
				(width 0.1)
				(type default)
			)
			(layer "B.Fab")
		)
		(fp_line
			(start 0.299974 0.150114)
			(end 0.299974 -0.150114)
			(stroke
				(width 0.1)
				(type default)
			)
			(layer "B.Fab")
		)
		(fp_line
			(start -0.299974 -0.150114)
			(end -0.299974 0.150114)
			(stroke
				(width 0.1)
				(type default)
			)
			(layer "B.Fab")
		)
		(fp_line
			(start 0.299974 -0.150114)
			(end -0.299974 -0.150114)
			(stroke
				(width 0.1)
				(type default)
			)
			(layer "B.Fab")
		)
		(pad "1" smd rect
			(at 0.2667 0 90)
			(size 0.3048 0.381)
			(layers "B.Cu" "B.Mask" "B.Paste")
			(net "P0V8_PEX1")
		)
		(pad "2" smd rect
			(at -0.2667 0 90)
			(size 0.3048 0.381)
			(layers "B.Cu" "B.Mask" "B.Paste")
			(net "GND")
		)
	)
)
